# T6G (Grand Teton) — schematic netlist excerpt (pin names and nets, part order shuffled) for the footprints in the layout excerpt that follows; sources: Cadence DE-HDL packaged netlist, KiCad conversion of 04192023_DAF0TMB3IC0_F0TG_MB_C_brd_V02_OCP.brd

PC158  Q_CAP  560PF 50V 10% EMPTY  pkg C0402  page 205 : A = SW_PVDDIO_P0_SW1 ; B = SW_PVDDIO_P0_SW1_RC
PR121  Q_RES  0 5% CHIP  pkg 0402LF  page 207 : A = VSENSE_PVDD11_S3_P0_DP ; B = VSENSE_PVDD11_S3_P0_R

(kicad_pcb
	(version 20260206)
	(generator "pcbnew")
	(generator_version "10.0")
	(general
		(thickness 1.6)
		(legacy_teardrops no)
	)
	(paper "A4")
	(title_block
		(title "04192023_DAF0TMB3IC0_F0TG_MB_C_brd_V02_OCP.brd")
		(comment 1 "Grand Teton / footprints 1054-1055 of 8354")
	)
	(layers
		(0 "F.Cu" signal "TOP")
		(4 "In1.Cu" signal "GND")
		(6 "In2.Cu" signal "IN1")
		(8 "In3.Cu" signal "GND1")
		(10 "In4.Cu" signal "IN2")
		(12 "In5.Cu" signal "GND2")
		(14 "In6.Cu" signal "IN3")
		(16 "In7.Cu" signal "GND3")
		(18 "In8.Cu" signal "VCC")
		(20 "In9.Cu" signal "VCC1")
		(22 "In10.Cu" signal "GND4")
		(24 "In11.Cu" signal "IN4")
		(26 "In12.Cu" signal "GND5")
		(28 "In13.Cu" signal "IN5")
		(30 "In14.Cu" signal "GND6")
		(32 "In15.Cu" signal "IN6")
		(34 "In16.Cu" signal "GND7")
		(2 "B.Cu" signal "BOTTOM")
		(9 "F.Adhes" user "F.Adhesive")
		(11 "B.Adhes" user "B.Adhesive")
		(13 "F.Paste" user "Package Geometry/Pastemask Top")
		(15 "B.Paste" user "Package Geometry/Pastemask Bottom")
		(5 "F.SilkS" user "Ref Des/Silkscreen Top")
		(7 "B.SilkS" user "Ref Des/Silkscreen Bottom")
		(1 "F.Mask" user "Board Geometry/Soldermask Top")
		(3 "B.Mask" user "Board Geometry/Soldermask Bottom")
		(17 "Dwgs.User" user "User.Drawings")
		(19 "Cmts.User" user "User.Comments")
		(21 "Eco1.User" user "User.Eco1")
		(23 "Eco2.User" user "User.Eco2")
		(25 "Edge.Cuts" user "Board Geometry/Outline")
		(27 "Margin" user)
		(31 "F.CrtYd" user "Package Geometry/Place Bound Top")
		(29 "B.CrtYd" user "Package Geometry/Place Bound Bottom")
		(35 "F.Fab" user "Ref Des/Assembly Top")
		(33 "B.Fab" user "Ref Des/Assembly Bottom")
	)
	(footprint ""
		(layer "F.Cu")
		(at 415.119058 -357.61676 90)
		(property "Reference" "PR121"
			(at 0 0 90)
			(layer "F.SilkS")
			(hide yes)
			(effects
				(font
					(size 1.27 1.27)
				)
			)
		)
		(property "Value" ""
			(at 0 0 90)
			(layer "F.Fab")
			(effects
				(font
					(size 1.27 1.27)
				)
			)
		)
		(duplicate_pad_numbers_are_jumpers no)
		(fp_line
			(start 0.7874 -0.4064)
			(end 0.7874 0.4064)
			(stroke
				(width 0.1524)
				(type default)
			)
			(layer "F.SilkS")
		)
		(fp_line
			(start -0.7874 -0.4064)
			(end 0.7874 -0.4064)
			(stroke
				(width 0.1524)
				(type default)
			)
			(layer "F.SilkS")
		)
		(fp_line
			(start 0.7874 0.4064)
			(end -0.7874 0.4064)
			(stroke
				(width 0.1524)
				(type default)
			)
			(layer "F.SilkS")
		)
		(fp_line
			(start -0.7874 0.4064)
			(end -0.7874 -0.4064)
			(stroke
				(width 0.1524)
				(type default)
			)
			(layer "F.SilkS")
		)
		(fp_line
			(start -0.12065 -0.305054)
			(end -0.12065 -0.2794)
			(stroke
				(width 0.1)
				(type default)
			)
			(layer "F.Fab")
		)
		(fp_line
			(start -0.67945 -0.305054)
			(end -0.12065 -0.305054)
			(stroke
				(width 0.1)
				(type default)
			)
			(layer "F.Fab")
		)
		(fp_line
			(start 0.67945 -0.3048)
			(end 0.67945 0.3048)
			(stroke
				(width 0.1)
				(type default)
			)
			(layer "F.Fab")
		)
		(fp_line
			(start 0.12065 -0.3048)
			(end 0.67945 -0.3048)
			(stroke
				(width 0.1)
				(type default)
			)
			(layer "F.Fab")
		)
		(fp_line
			(start 0.12065 -0.2794)
			(end 0.12065 -0.3048)
			(stroke
				(width 0.1)
				(type default)
			)
			(layer "F.Fab")
		)
		(fp_line
			(start -0.12065 -0.2794)
			(end 0.12065 -0.2794)
			(stroke
				(width 0.1)
				(type default)
			)
			(layer "F.Fab")
		)
		(fp_line
			(start 0.120396 0.2794)
			(end -0.12065 0.2794)
			(stroke
				(width 0.1)
				(type default)
			)
			(layer "F.Fab")
		)
		(fp_line
			(start -0.12065 0.2794)
			(end -0.12065 0.3048)
			(stroke
				(width 0.1)
				(type default)
			)
			(layer "F.Fab")
		)
		(fp_line
			(start 0.67945 0.3048)
			(end 0.120396 0.3048)
			(stroke
				(width 0.1)
				(type default)
			)
			(layer "F.Fab")
		)
		(fp_line
			(start 0.120396 0.3048)
			(end 0.120396 0.2794)
			(stroke
				(width 0.1)
				(type default)
			)
			(layer "F.Fab")
		)
		(fp_line
			(start -0.12065 0.3048)
			(end -0.67945 0.3048)
			(stroke
				(width 0.1)
				(type default)
			)
			(layer "F.Fab")
		)
		(fp_line
			(start -0.67945 0.3048)
			(end -0.67945 -0.305054)
			(stroke
				(width 0.1)
				(type default)
			)
			(layer "F.Fab")
		)
		(pad "1" smd circle
			(at -0.40005 0 90)
			(size 0 0)
			(layers "F.Cu" "F.Mask" "F.Paste")
			(net "VSENSE_PVDD11_S3_P0_DP")
		)
		(pad "2" smd circle
			(at 0.40005 0 90)
			(size 0 0)
			(layers "F.Cu" "F.Mask" "F.Paste")
			(net "VSENSE_PVDD11_S3_P0_R")
		)
	)
	(footprint ""
		(layer "F.Cu")
		(at 296.670984 -343.712038 180)
		(property "Reference" "PC158"
			(at 0 0 180)
			(layer "F.SilkS")
			(hide yes)
			(effects
				(font
					(size 1.27 1.27)
				)
			)
		)
		(property "Value" ""
			(at 0 0 180)
			(layer "F.Fab")
			(effects
				(font
					(size 1.27 1.27)
				)
			)
		)
		(duplicate_pad_numbers_are_jumpers no)
		(fp_line
			(start 0.7874 0.4064)
			(end -0.7874 0.4064)
			(stroke
				(width 0.1524)
				(type default)
			)
			(layer "F.SilkS")
		)
		(fp_line
			(start 0.7874 -0.4064)
			(end 0.7874 0.4064)
			(stroke
				(width 0.1524)
				(type default)
			)
			(layer "F.SilkS")
		)
		(fp_line
			(start -0.7874 0.4064)
			(end -0.7874 -0.4064)
			(stroke
				(width 0.1524)
				(type default)
			)
			(layer "F.SilkS")
		)
		(fp_line
			(start -0.7874 -0.4064)
			(end 0.7874 -0.4064)
			(stroke
				(width 0.1524)
				(type default)
			)
			(layer "F.SilkS")
		)
		(fp_line
			(start 0.67945 0.3048)
			(end 0.120396 0.3048)
			(stroke
				(width 0.1)
				(type default)
			)
			(layer "F.Fab")
		)
		(fp_line
			(start 0.67945 -0.3048)
			(end 0.67945 0.3048)
			(stroke
				(width 0.1)
				(type default)
			)
			(layer "F.Fab")
		)
		(fp_line
			(start 0.12065 -0.2794)
			(end 0.12065 -0.3048)
			(stroke
				(width 0.1)
				(type default)
			)
			(layer "F.Fab")
		)
		(fp_line
			(start 0.12065 -0.3048)
			(end 0.67945 -0.3048)
			(stroke
				(width 0.1)
				(type default)
			)
			(layer "F.Fab")
		)
		(fp_line
			(start 0.120396 0.3048)
			(end 0.120396 0.2794)
			(stroke
				(width 0.1)
				(type default)
			)
			(layer "F.Fab")
		)
		(fp_line
			(start 0.120396 0.2794)
			(end -0.12065 0.2794)
			(stroke
				(width 0.1)
				(type default)
			)
			(layer "F.Fab")
		)
		(fp_line
			(start -0.12065 0.3048)
			(end -0.67945 0.3048)
			(stroke
				(width 0.1)
				(type default)
			)
			(layer "F.Fab")
		)
		(fp_line
			(start -0.12065 0.2794)
			(end -0.12065 0.3048)
			(stroke
				(width 0.1)
				(type default)
			)
			(layer "F.Fab")
		)
		(fp_line
			(start -0.12065 -0.2794)
			(end 0.12065 -0.2794)
			(stroke
				(width 0.1)
				(type default)
			)
			(layer "F.Fab")
		)
		(fp_line
			(start -0.12065 -0.305054)
			(end -0.12065 -0.2794)
			(stroke
				(width 0.1)
				(type default)
			)
			(layer "F.Fab")
		)
		(fp_line
			(start -0.67945 0.3048)
			(end -0.67945 -0.305054)
			(stroke
				(width 0.1)
				(type default)
			)
			(layer "F.Fab")
		)
		(fp_line
			(start -0.67945 -0.305054)
			(end -0.12065 -0.305054)
			(stroke
				(width 0.1)
				(type default)
			)
			(layer "F.Fab")
		)
		(pad "1" smd circle
			(at -0.40005 0 180)
			(size 0 0)
			(layers "F.Cu" "F.Mask" "F.Paste")
			(net "SW_PVDDIO_P0_SW1")
		)
		(pad "2" smd circle
			(at 0.40005 0 180)
			(size 0 0)
			(layers "F.Cu" "F.Mask" "F.Paste")
			(net "SW_PVDDIO_P0_SW1_RC")
		)
	)
)
